# S9S_MB_2U (Grand Teton) — schematic netlist excerpt (pin names and nets, part order shuffled) for the footprints in the layout excerpt that follows; sources: Cadence DE-HDL packaged netlist, KiCad conversion of 03242023_DA0F0TMBIJ0_F0T_Motherboard_J_brd_V01_OCP.brd

R3091  Q_RES  130 1% CHIP  pkg 0402LF  page 253 : A = LED_PWRGD_PVCCIN_CPU0 ; B = P3V3_AUX
PR1770  Q_RES  3.3 1% CHIP  pkg 0402LF  page 269 : A = SW_PVCCIN_CPU0_BOOT6 ; B = SW_PVCCIN_CPU0_BOOT6_R

(kicad_pcb
	(version 20260206)
	(generator "pcbnew")
	(generator_version "10.0")
	(general
		(thickness 1.6)
		(legacy_teardrops no)
	)
	(paper "A4")
	(title_block
		(title "03242023_DA0F0TMBIJ0_F0T_Motherboard_J_brd_V01_OCP.brd")
		(comment 1 "Grand Teton / footprints 262-263 of 6105")
	)
	(layers
		(0 "F.Cu" signal "TOP")
		(4 "In1.Cu" signal "GND")
		(6 "In2.Cu" signal "IN1")
		(8 "In3.Cu" signal "GND1")
		(10 "In4.Cu" signal "IN2")
		(12 "In5.Cu" signal "GND2")
		(14 "In6.Cu" signal "IN3")
		(16 "In7.Cu" signal "GND3")
		(18 "In8.Cu" signal "VCC")
		(20 "In9.Cu" signal "VCC1")
		(22 "In10.Cu" signal "GND4")
		(24 "In11.Cu" signal "IN4")
		(26 "In12.Cu" signal "GND5")
		(28 "In13.Cu" signal "IN5")
		(30 "In14.Cu" signal "GND6")
		(32 "In15.Cu" signal "IN6")
		(34 "In16.Cu" signal "GND7")
		(2 "B.Cu" signal "BOTTOM")
		(9 "F.Adhes" user "F.Adhesive")
		(11 "B.Adhes" user "B.Adhesive")
		(13 "F.Paste" user "Package Geometry/Pastemask Top")
		(15 "B.Paste" user "Package Geometry/Pastemask Bottom")
		(5 "F.SilkS" user "Ref Des/Silkscreen Top")
		(7 "B.SilkS" user "Ref Des/Silkscreen Bottom")
		(1 "F.Mask" user "Board Geometry/Soldermask Top")
		(3 "B.Mask" user "Board Geometry/Soldermask Bottom")
		(17 "Dwgs.User" user "User.Drawings")
		(19 "Cmts.User" user "User.Comments")
		(21 "Eco1.User" user "User.Eco1")
		(23 "Eco2.User" user "User.Eco2")
		(25 "Edge.Cuts" user "Board Geometry/Outline")
		(27 "Margin" user)
		(31 "F.CrtYd" user "Package Geometry/Place Bound Top")
		(29 "B.CrtYd" user "Package Geometry/Place Bound Bottom")
		(35 "F.Fab" user "Ref Des/Assembly Top")
		(33 "B.Fab" user "Ref Des/Assembly Bottom")
	)
	(footprint ""
		(layer "F.Cu")
		(at 99.724464 -65.141094 -90)
		(property "Reference" "R3091"
			(at 0 0 270)
			(layer "F.SilkS")
			(hide yes)
			(effects
				(font
					(size 1.27 1.27)
				)
			)
		)
		(property "Value" ""
			(at 0 0 270)
			(layer "F.Fab")
			(effects
				(font
					(size 1.27 1.27)
				)
			)
		)
		(duplicate_pad_numbers_are_jumpers no)
		(fp_line
			(start -0.7874 0.4064)
			(end -0.7874 -0.4064)
			(stroke
				(width 0.1524)
				(type default)
			)
			(layer "F.SilkS")
		)
		(fp_line
			(start 0.7874 0.4064)
			(end -0.7874 0.4064)
			(stroke
				(width 0.1524)
				(type default)
			)
			(layer "F.SilkS")
		)
		(fp_line
			(start -0.7874 -0.4064)
			(end 0.7874 -0.4064)
			(stroke
				(width 0.1524)
				(type default)
			)
			(layer "F.SilkS")
		)
		(fp_line
			(start 0.7874 -0.4064)
			(end 0.7874 0.4064)
			(stroke
				(width 0.1524)
				(type default)
			)
			(layer "F.SilkS")
		)
		(fp_line
			(start -0.67945 0.3048)
			(end -0.67945 -0.305054)
			(stroke
				(width 0.1)
				(type default)
			)
			(layer "F.Fab")
		)
		(fp_line
			(start -0.12065 0.3048)
			(end -0.67945 0.3048)
			(stroke
				(width 0.1)
				(type default)
			)
			(layer "F.Fab")
		)
		(fp_line
			(start 0.120396 0.3048)
			(end 0.120396 0.2794)
			(stroke
				(width 0.1)
				(type default)
			)
			(layer "F.Fab")
		)
		(fp_line
			(start 0.67945 0.3048)
			(end 0.120396 0.3048)
			(stroke
				(width 0.1)
				(type default)
			)
			(layer "F.Fab")
		)
		(fp_line
			(start -0.12065 0.2794)
			(end -0.12065 0.3048)
			(stroke
				(width 0.1)
				(type default)
			)
			(layer "F.Fab")
		)
		(fp_line
			(start 0.120396 0.2794)
			(end -0.12065 0.2794)
			(stroke
				(width 0.1)
				(type default)
			)
			(layer "F.Fab")
		)
		(fp_line
			(start -0.12065 -0.2794)
			(end 0.12065 -0.2794)
			(stroke
				(width 0.1)
				(type default)
			)
			(layer "F.Fab")
		)
		(fp_line
			(start 0.12065 -0.2794)
			(end 0.12065 -0.3048)
			(stroke
				(width 0.1)
				(type default)
			)
			(layer "F.Fab")
		)
		(fp_line
			(start 0.12065 -0.3048)
			(end 0.67945 -0.3048)
			(stroke
				(width 0.1)
				(type default)
			)
			(layer "F.Fab")
		)
		(fp_line
			(start 0.67945 -0.3048)
			(end 0.67945 0.3048)
			(stroke
				(width 0.1)
				(type default)
			)
			(layer "F.Fab")
		)
		(fp_line
			(start -0.67945 -0.305054)
			(end -0.12065 -0.305054)
			(stroke
				(width 0.1)
				(type default)
			)
			(layer "F.Fab")
		)
		(fp_line
			(start -0.12065 -0.305054)
			(end -0.12065 -0.2794)
			(stroke
				(width 0.1)
				(type default)
			)
			(layer "F.Fab")
		)
		(pad "1" smd circle
			(at -0.40005 0 270)
			(size 0 0)
			(layers "F.Cu" "F.Mask" "F.Paste")
			(net "LED_PWRGD_PVCCIN_CPU0")
		)
		(pad "2" smd circle
			(at 0.40005 0 270)
			(size 0 0)
			(layers "F.Cu" "F.Mask" "F.Paste")
			(net "P3V3_AUX")
		)
	)
	(footprint ""
		(layer "F.Cu")
		(at 337.536282 -341.729822 90)
		(property "Reference" "PR1770"
			(at 0 0 90)
			(layer "F.SilkS")
			(hide yes)
			(effects
				(font
					(size 1.27 1.27)
				)
			)
		)
		(property "Value" ""
			(at 0 0 90)
			(layer "F.Fab")
			(effects
				(font
					(size 1.27 1.27)
				)
			)
		)
		(duplicate_pad_numbers_are_jumpers no)
		(fp_line
			(start 0.7874 -0.4064)
			(end 0.7874 0.4064)
			(stroke
				(width 0.1524)
				(type default)
			)
			(layer "F.SilkS")
		)
		(fp_line
			(start -0.7874 -0.4064)
			(end 0.7874 -0.4064)
			(stroke
				(width 0.1524)
				(type default)
			)
			(layer "F.SilkS")
		)
		(fp_line
			(start 0.7874 0.4064)
			(end -0.7874 0.4064)
			(stroke
				(width 0.1524)
				(type default)
			)
			(layer "F.SilkS")
		)
		(fp_line
			(start -0.7874 0.4064)
			(end -0.7874 -0.4064)
			(stroke
				(width 0.1524)
				(type default)
			)
			(layer "F.SilkS")
		)
		(fp_line
			(start -0.12065 -0.305054)
			(end -0.12065 -0.2794)
			(stroke
				(width 0.1)
				(type default)
			)
			(layer "F.Fab")
		)
		(fp_line
			(start -0.67945 -0.305054)
			(end -0.12065 -0.305054)
			(stroke
				(width 0.1)
				(type default)
			)
			(layer "F.Fab")
		)
		(fp_line
			(start 0.67945 -0.3048)
			(end 0.67945 0.3048)
			(stroke
				(width 0.1)
				(type default)
			)
			(layer "F.Fab")
		)
		(fp_line
			(start 0.12065 -0.3048)
			(end 0.67945 -0.3048)
			(stroke
				(width 0.1)
				(type default)
			)
			(layer "F.Fab")
		)
		(fp_line
			(start 0.12065 -0.2794)
			(end 0.12065 -0.3048)
			(stroke
				(width 0.1)
				(type default)
			)
			(layer "F.Fab")
		)
		(fp_line
			(start -0.12065 -0.2794)
			(end 0.12065 -0.2794)
			(stroke
				(width 0.1)
				(type default)
			)
			(layer "F.Fab")
		)
		(fp_line
			(start 0.120396 0.2794)
			(end -0.12065 0.2794)
			(stroke
				(width 0.1)
				(type default)
			)
			(layer "F.Fab")
		)
		(fp_line
			(start -0.12065 0.2794)
			(end -0.12065 0.3048)
			(stroke
				(width 0.1)
				(type default)
			)
			(layer "F.Fab")
		)
		(fp_line
			(start 0.67945 0.3048)
			(end 0.120396 0.3048)
			(stroke
				(width 0.1)
				(type default)
			)
			(layer "F.Fab")
		)
		(fp_line
			(start 0.120396 0.3048)
			(end 0.120396 0.2794)
			(stroke
				(width 0.1)
				(type default)
			)
			(layer "F.Fab")
		)
		(fp_line
			(start -0.12065 0.3048)
			(end -0.67945 0.3048)
			(stroke
				(width 0.1)
				(type default)
			)
			(layer "F.Fab")
		)
		(fp_line
			(start -0.67945 0.3048)
			(end -0.67945 -0.305054)
			(stroke
				(width 0.1)
				(type default)
			)
			(layer "F.Fab")
		)
		(pad "1" smd circle
			(at -0.40005 0 90)
			(size 0 0)
			(layers "F.Cu" "F.Mask" "F.Paste")
			(net "SW_PVCCIN_CPU0_BOOT6")
		)
		(pad "2" smd circle
			(at 0.40005 0 90)
			(size 0 0)
			(layers "F.Cu" "F.Mask" "F.Paste")
			(net "SW_PVCCIN_CPU0_BOOT6_R")
		)
	)
)
